# BASEBOARD_FAB2 (Tioga Pass) — schematic netlist excerpt (pin names and nets, part order shuffled) for the footprints in the layout excerpt that follows; sources: Cadence DE-HDL packaged netlist, KiCad conversion of Wiwynn_Tioga_Pass_MB.brd

C1G11  CAP  0.220UF 16V 10% X7R  pkg 0402  page 224 : A = VR_PVDDQ_GHJ_PH1_BOOT ; B = VR_PVDDQ_GHJ_PH1_PHASE
C3D18  CAP_A  22.0UF 4V 20% X6S  pkg 0603V  page 76 : A = PVCCMCP_CPU1 ; B = GND
C9W5  CAP_A  0.1UF 16V 10% X7R  pkg 0402V  page 239 : A = P3V3_STBY ; B = GND

(kicad_pcb
	(version 20260206)
	(generator "pcbnew")
	(generator_version "10.0")
	(general
		(thickness 1.6)
		(legacy_teardrops no)
	)
	(paper "A4")
	(title_block
		(title "Wiwynn_Tioga_Pass_MB.brd")
		(comment 1 "Tioga Pass / footprints 1168-1170 of 4770")
	)
	(layers
		(0 "F.Cu" signal "TOP")
		(4 "In1.Cu" signal "L2GND")
		(6 "In2.Cu" signal "L3")
		(8 "In3.Cu" signal "L4GND")
		(10 "In4.Cu" signal "L5")
		(12 "In5.Cu" signal "L6GND")
		(14 "In6.Cu" signal "L7VCC")
		(16 "In7.Cu" signal "L8VCC")
		(18 "In8.Cu" signal "L9GND")
		(20 "In9.Cu" signal "L10")
		(22 "In10.Cu" signal "L11GND")
		(24 "In11.Cu" signal "L12")
		(26 "In12.Cu" signal "L13GND")
		(2 "B.Cu" signal "BOTTOM")
		(9 "F.Adhes" user "F.Adhesive")
		(11 "B.Adhes" user "B.Adhesive")
		(13 "F.Paste" user "Package Geometry/Pastemask Top")
		(15 "B.Paste" user "Package Geometry/Pastemask Bottom")
		(5 "F.SilkS" user "Ref Des/Silkscreen Top")
		(7 "B.SilkS" user "Ref Des/Silkscreen Bottom")
		(1 "F.Mask" user "Board Geometry/Soldermask Top")
		(3 "B.Mask" user "Board Geometry/Soldermask Bottom")
		(17 "Dwgs.User" user "User.Drawings")
		(19 "Cmts.User" user "User.Comments")
		(21 "Eco1.User" user "User.Eco1")
		(23 "Eco2.User" user "User.Eco2")
		(25 "Edge.Cuts" user "Board Geometry/Outline")
		(27 "Margin" user)
		(31 "F.CrtYd" user "Package Geometry/Place Bound Top")
		(29 "B.CrtYd" user "Package Geometry/Place Bound Bottom")
		(35 "F.Fab" user "Ref Des/Assembly Top")
		(33 "B.Fab" user "Ref Des/Assembly Bottom")
	)
	(footprint ""
		(layer "F.Cu")
		(at 456.2475 -25.8572 -90)
		(property "Reference" "C9W5"
			(at -0.8382 -0.67818 270)
			(unlocked yes)
			(layer "F.SilkS")
			(effects
				(font
					(size 0.4064 0.254)
					(thickness 0.1524)
				)
				(justify left)
			)
		)
		(property "Value" ""
			(at 0 0 270)
			(layer "F.Fab")
			(effects
				(font
					(size 1.27 1.27)
				)
			)
		)
		(duplicate_pad_numbers_are_jumpers no)
		(fp_poly
			(pts
				(xy 0.3048 -0.1016) (xy 0.3048 0.9906) (xy -0.3048 0.9906) (xy -0.3048 -0.1016)
			)
			(stroke
				(width 0)
				(type default)
			)
			(fill no)
			(layer "F.CrtYd")
		)
		(fp_line
			(start -0.3048 0.9906)
			(end 0.3048 0.9906)
			(stroke
				(width 0.1)
				(type default)
			)
			(layer "F.Fab")
		)
		(fp_line
			(start 0.3048 0.9906)
			(end 0.3048 -0.1016)
			(stroke
				(width 0.1)
				(type default)
			)
			(layer "F.Fab")
		)
		(fp_line
			(start -0.3048 -0.1016)
			(end -0.3048 0.9906)
			(stroke
				(width 0.1)
				(type default)
			)
			(layer "F.Fab")
		)
		(fp_line
			(start 0.3048 -0.1016)
			(end -0.3048 -0.1016)
			(stroke
				(width 0.1)
				(type default)
			)
			(layer "F.Fab")
		)
		(pad "1" smd rect
			(at 0 0 270)
			(size 0.508 0.508)
			(layers "F.Cu" "F.Mask" "F.Paste")
			(net "P3V3_STBY")
		)
		(pad "2" smd rect
			(at 0 0.889 270)
			(size 0.508 0.508)
			(layers "F.Cu" "F.Mask" "F.Paste")
			(net "GND")
		)
		(zone
			(layer "F.Cu")
			(hatch none 0.5)
			(connect_pads
				(clearance 0)
			)
			(min_thickness 0.25)
			(keepout
				(tracks not_allowed)
				(vias allowed)
				(pads allowed)
				(copperpour not_allowed)
				(footprints allowed)
			)
			(placement
				(enabled no)
				(sheetname "")
			)
			(fill
				(thermal_gap 0.5)
				(thermal_bridge_width 0.5)
				(island_removal_mode 0)
			)
			(polygon
				(pts
					(xy 455.6125 -26.1112) (xy 455.6125 -25.6032) (xy 455.9935 -25.6032) (xy 455.9935 -26.1112)
				)
			)
		)
		(zone
			(layer "F.Cu")
			(hatch none 0.5)
			(connect_pads
				(clearance 0)
			)
			(min_thickness 0.25)
			(keepout
				(tracks allowed)
				(vias not_allowed)
				(pads allowed)
				(copperpour not_allowed)
				(footprints allowed)
			)
			(placement
				(enabled no)
				(sheetname "")
			)
			(fill
				(thermal_gap 0.5)
				(thermal_bridge_width 0.5)
				(island_removal_mode 0)
			)
			(polygon
				(pts
					(xy 455.9935 -26.1112) (xy 455.9935 -25.6032) (xy 455.6125 -25.6032) (xy 455.6125 -26.1112)
				)
			)
		)
	)
	(footprint ""
		(layer "F.Cu")
		(at 109.43844 -73.318116)
		(property "Reference" "C3D18"
			(at 0 0 0)
			(layer "F.SilkS")
			(hide yes)
			(effects
				(font
					(size 1.27 1.27)
				)
			)
		)
		(property "Value" ""
			(at 0 0 0)
			(layer "F.Fab")
			(effects
				(font
					(size 1.27 1.27)
				)
			)
		)
		(duplicate_pad_numbers_are_jumpers no)
		(fp_poly
			(pts
				(xy -0.4953 -0.2032) (xy 0.4953 -0.2032) (xy 0.4953 1.6002) (xy -0.4953 1.6002)
			)
			(stroke
				(width 0)
				(type default)
			)
			(fill no)
			(layer "F.CrtYd")
		)
		(fp_line
			(start -0.4953 -0.2032)
			(end 0.4953 -0.2032)
			(stroke
				(width 0.1)
				(type default)
			)
			(layer "F.Fab")
		)
		(fp_line
			(start -0.4953 1.6002)
			(end -0.4953 -0.2032)
			(stroke
				(width 0.1)
				(type default)
			)
			(layer "F.Fab")
		)
		(fp_line
			(start 0.4953 -0.2032)
			(end 0.4953 1.6002)
			(stroke
				(width 0.1)
				(type default)
			)
			(layer "F.Fab")
		)
		(fp_line
			(start 0.4953 1.6002)
			(end -0.4953 1.6002)
			(stroke
				(width 0.1)
				(type default)
			)
			(layer "F.Fab")
		)
		(pad "1" smd rect
			(at 0 0)
			(size 0.762 0.889)
			(layers "F.Cu" "F.Mask" "F.Paste")
			(net "PVCCMCP_CPU1")
		)
		(pad "2" smd rect
			(at 0 1.397)
			(size 0.762 0.889)
			(layers "F.Cu" "F.Mask" "F.Paste")
			(net "GND")
		)
		(zone
			(layer "F.Cu")
			(hatch none 0.5)
			(connect_pads
				(clearance 0)
			)
			(min_thickness 0.25)
			(keepout
				(tracks not_allowed)
				(vias allowed)
				(pads allowed)
				(copperpour not_allowed)
				(footprints allowed)
			)
			(placement
				(enabled no)
				(sheetname "")
			)
			(fill
				(thermal_gap 0.5)
				(thermal_bridge_width 0.5)
				(island_removal_mode 0)
			)
			(polygon
				(pts
					(xy 109.05744 -72.873616) (xy 109.81944 -72.873616) (xy 109.81944 -72.365616) (xy 109.05744 -72.365616)
				)
			)
		)
	)
	(footprint ""
		(layer "F.Cu")
		(at 0.55118 -12.97432 90)
		(property "Reference" "C1G11"
			(at 0 0 90)
			(layer "F.SilkS")
			(hide yes)
			(effects
				(font
					(size 1.27 1.27)
				)
			)
		)
		(property "Value" ""
			(at 0 0 90)
			(layer "F.Fab")
			(effects
				(font
					(size 1.27 1.27)
				)
			)
		)
		(duplicate_pad_numbers_are_jumpers no)
		(fp_rect
			(start -0.3048 -0.1016)
			(end 0.3048 0.9906)
			(stroke
				(width 0)
				(type default)
			)
			(fill no)
			(layer "F.CrtYd")
		)
		(fp_line
			(start 0.3048 -0.1016)
			(end -0.3048 -0.1016)
			(stroke
				(width 0.1)
				(type default)
			)
			(layer "F.Fab")
		)
		(fp_line
			(start -0.3048 -0.1016)
			(end -0.3048 0.9906)
			(stroke
				(width 0.1)
				(type default)
			)
			(layer "F.Fab")
		)
		(fp_line
			(start 0.3048 0.9906)
			(end 0.3048 -0.1016)
			(stroke
				(width 0.1)
				(type default)
			)
			(layer "F.Fab")
		)
		(fp_line
			(start -0.3048 0.9906)
			(end 0.3048 0.9906)
			(stroke
				(width 0.1)
				(type default)
			)
			(layer "F.Fab")
		)
		(pad "1" smd rect
			(at 0 0 90)
			(size 0.508 0.508)
			(layers "F.Cu" "F.Mask" "F.Paste")
			(net "VR_PVDDQ_GHJ_PH1_BOOT")
		)
		(pad "2" smd rect
			(at 0 0.889 90)
			(size 0.508 0.508)
			(layers "F.Cu" "F.Mask" "F.Paste")
			(net "VR_PVDDQ_GHJ_PH1_PHASE")
		)
		(zone
			(layer "F.Cu")
			(hatch none 0.5)
			(connect_pads
				(clearance 0)
			)
			(min_thickness 0.25)
			(keepout
				(tracks not_allowed)
				(vias allowed)
				(pads allowed)
				(copperpour not_allowed)
				(footprints allowed)
			)
			(placement
				(enabled no)
				(sheetname "")
			)
			(fill
				(thermal_gap 0.5)
				(thermal_bridge_width 0.5)
				(island_removal_mode 0)
			)
			(polygon
				(pts
					(xy 0.80518 -12.72032) (xy 1.18618 -12.72032) (xy 1.18618 -13.22832) (xy 0.80518 -13.22832)
				)
			)
		)
		(zone
			(layer "F.Cu")
			(hatch none 0.5)
			(connect_pads
				(clearance 0)
			)
			(min_thickness 0.25)
			(keepout
				(tracks allowed)
				(vias not_allowed)
				(pads allowed)
				(copperpour not_allowed)
				(footprints allowed)
			)
			(placement
				(enabled no)
				(sheetname "")
			)
			(fill
				(thermal_gap 0.5)
				(thermal_bridge_width 0.5)
				(island_removal_mode 0)
			)
			(polygon
				(pts
					(xy 0.80518 -12.72032) (xy 1.18618 -12.72032) (xy 1.18618 -13.22832) (xy 0.80518 -13.22832)
				)
			)
		)
	)
)
